(kicad_pcb
	(version 20260206)
	(generator "pcbnew")
	(generator_version "10.0")
	(general
		(thickness 1.6)
		(legacy_teardrops no)
	)
	(paper "A4")
	(title_block
		(title "Bryce Canyon_SCC_16316-1_OCP.brd")
		(comment 1 "Bryce Canyon / footprints 1363-1370 of 1561")
	)
	(layers
		(0 "F.Cu" signal "TOP")
		(4 "In1.Cu" signal "L2GND")
		(6 "In2.Cu" signal "L3")
		(8 "In3.Cu" signal "L4VCC")
		(10 "In4.Cu" signal "L5VCC")
		(12 "In5.Cu" signal "L6")
		(14 "In6.Cu" signal "L7GND")
		(2 "B.Cu" signal "BOTTOM")
		(9 "F.Adhes" user "F.Adhesive")
		(11 "B.Adhes" user "B.Adhesive")
		(13 "F.Paste" user "Package Geometry/Pastemask Top")
		(15 "B.Paste" user "Package Geometry/Pastemask Bottom")
		(5 "F.SilkS" user "Ref Des/Silkscreen Top")
		(7 "B.SilkS" user "Ref Des/Silkscreen Bottom")
		(1 "F.Mask" user "Board Geometry/Soldermask Top")
		(3 "B.Mask" user "Board Geometry/Soldermask Bottom")
		(17 "Dwgs.User" user "User.Drawings")
		(19 "Cmts.User" user "User.Comments")
		(21 "Eco1.User" user "User.Eco1")
		(23 "Eco2.User" user "User.Eco2")
		(25 "Edge.Cuts" user "Board Geometry/Outline")
		(27 "Margin" user)
		(31 "F.CrtYd" user "Package Geometry/Place Bound Top")
		(29 "B.CrtYd" user "Package Geometry/Place Bound Bottom")
		(35 "F.Fab" user "Ref Des/Assembly Top")
		(33 "B.Fab" user "Ref Des/Assembly Bottom")
	)
	(footprint ""
		(layer "B.Cu")
		(at 117.3353 -64.4779)
		(property "Reference" "C160"
			(at 0 0 0)
			(layer "B.SilkS")
			(hide yes)
			(effects
				(font
					(size 1.27 1.27)
				)
				(justify mirror)
			)
		)
		(property "Value" "SCD1U6D3V1KX-GP"
			(at 2.8321 -1.7399 0)
			(unlocked yes)
			(layer "B.Fab")
			(hide yes)
			(effects
				(font
					(size 1.016 1.016)
					(thickness 0.1524)
				)
				(justify mirror)
			)
		)
		(property "Device Type" "C0201H13"
			(at 2.8321 -3.2639 0)
			(unlocked yes)
			(layer "B.Fab")
			(hide yes)
			(effects
				(font
					(size 1.016 1.016)
					(thickness 0.1524)
				)
				(justify mirror)
			)
		)
		(duplicate_pad_numbers_are_jumpers no)
		(fp_rect
			(start 0.2794 0.6477)
			(end -0.2794 -0.6477)
			(stroke
				(width 0)
				(type default)
			)
			(fill no)
			(layer "B.CrtYd")
		)
		(fp_rect
			(start 0.2794 0.6477)
			(end -0.2794 -0.6477)
			(stroke
				(width 0)
				(type default)
			)
			(fill no)
			(layer "B.Fab")
		)
		(pad "1" smd custom
			(at 0 -0.2794 180)
			(size 0.0762 0.0762)
			(layers "B.Cu" "B.Mask" "B.Paste")
			(net "P0V9")
			(options
				(clearance outline)
				(anchor circle)
			)
			(primitives
				(gr_poly
					(pts
						(arc
							(start 0.1524 0.127)
							(mid 0.137521 0.162921)
							(end 0.1016 0.1778)
						)
						(arc
							(start -0.1016 0.1778)
							(mid -0.137521 0.162921)
							(end -0.1524 0.127)
						)
						(arc
							(start -0.1524 -0.127)
							(mid -0.137521 -0.162921)
							(end -0.1016 -0.1778)
						)
						(arc
							(start 0.1016 -0.1778)
							(mid 0.137521 -0.162921)
							(end 0.1524 -0.127)
						)
					)
					(width 0)
					(fill yes)
				)
			)
		)
		(pad "2" smd custom
			(at 0 0.2794 180)
			(size 0.0762 0.0762)
			(layers "B.Cu" "B.Mask" "B.Paste")
			(net "GND")
			(options
				(clearance outline)
				(anchor circle)
			)
			(primitives
				(gr_poly
					(pts
						(arc
							(start 0.1524 0.127)
							(mid 0.137521 0.162921)
							(end 0.1016 0.1778)
						)
						(arc
							(start -0.1016 0.1778)
							(mid -0.137521 0.162921)
							(end -0.1524 0.127)
						)
						(arc
							(start -0.1524 -0.127)
							(mid -0.137521 -0.162921)
							(end -0.1016 -0.1778)
						)
						(arc
							(start 0.1016 -0.1778)
							(mid 0.137521 -0.162921)
							(end 0.1524 -0.127)
						)
					)
					(width 0)
					(fill yes)
				)
			)
		)
	)
	(footprint ""
		(layer "B.Cu")
		(at 173.7741 -42.90822 -90)
		(property "Reference" "C427"
			(at 0 0 90)
			(layer "B.SilkS")
			(hide yes)
			(effects
				(font
					(size 1.27 1.27)
				)
				(justify mirror)
			)
		)
		(property "Value" "SCD1U6D3V1KX-GP"
			(at 2.8321 -1.7399 270)
			(unlocked yes)
			(layer "B.Fab")
			(hide yes)
			(effects
				(font
					(size 1.016 1.016)
					(thickness 0.1524)
				)
				(justify mirror)
			)
		)
		(property "Device Type" "C0201H13"
			(at 2.8321 -3.2639 270)
			(unlocked yes)
			(layer "B.Fab")
			(hide yes)
			(effects
				(font
					(size 1.016 1.016)
					(thickness 0.1524)
				)
				(justify mirror)
			)
		)
		(duplicate_pad_numbers_are_jumpers no)
		(fp_rect
			(start 0.2794 0.6477)
			(end -0.2794 -0.6477)
			(stroke
				(width 0)
				(type default)
			)
			(fill no)
			(layer "B.CrtYd")
		)
		(fp_rect
			(start 0.2794 0.6477)
			(end -0.2794 -0.6477)
			(stroke
				(width 0)
				(type default)
			)
			(fill no)
			(layer "B.Fab")
		)
		(pad "1" smd custom
			(at 0 -0.2794 90)
			(size 0.0762 0.0762)
			(layers "B.Cu" "B.Mask" "B.Paste")
			(net "P0V975")
			(options
				(clearance outline)
				(anchor circle)
			)
			(primitives
				(gr_poly
					(pts
						(arc
							(start 0.1524 0.127)
							(mid 0.137521 0.162921)
							(end 0.1016 0.1778)
						)
						(arc
							(start -0.1016 0.1778)
							(mid -0.137521 0.162921)
							(end -0.1524 0.127)
						)
						(arc
							(start -0.1524 -0.127)
							(mid -0.137521 -0.162921)
							(end -0.1016 -0.1778)
						)
						(arc
							(start 0.1016 -0.1778)
							(mid 0.137521 -0.162921)
							(end 0.1524 -0.127)
						)
					)
					(width 0)
					(fill yes)
				)
			)
		)
		(pad "2" smd custom
			(at 0 0.2794 90)
			(size 0.0762 0.0762)
			(layers "B.Cu" "B.Mask" "B.Paste")
			(net "GND")
			(options
				(clearance outline)
				(anchor circle)
			)
			(primitives
				(gr_poly
					(pts
						(arc
							(start 0.1524 0.127)
							(mid 0.137521 0.162921)
							(end 0.1016 0.1778)
						)
						(arc
							(start -0.1016 0.1778)
							(mid -0.137521 0.162921)
							(end -0.1524 0.127)
						)
						(arc
							(start -0.1524 -0.127)
							(mid -0.137521 -0.162921)
							(end -0.1016 -0.1778)
						)
						(arc
							(start 0.1016 -0.1778)
							(mid 0.137521 -0.162921)
							(end 0.1524 -0.127)
						)
					)
					(width 0)
					(fill yes)
				)
			)
		)
	)
	(footprint ""
		(layer "B.Cu")
		(at 122.4788 -70.5104 -90)
		(property "Reference" "C280"
			(at 0 0 90)
			(layer "B.SilkS")
			(hide yes)
			(effects
				(font
					(size 1.27 1.27)
				)
				(justify mirror)
			)
		)
		(property "Value" "SCD1U6D3V1KX-GP"
			(at 2.8321 -1.7399 270)
			(unlocked yes)
			(layer "B.Fab")
			(hide yes)
			(effects
				(font
					(size 1.016 1.016)
					(thickness 0.1524)
				)
				(justify mirror)
			)
		)
		(property "Device Type" "C0201H13"
			(at 2.8321 -3.2639 270)
			(unlocked yes)
			(layer "B.Fab")
			(hide yes)
			(effects
				(font
					(size 1.016 1.016)
					(thickness 0.1524)
				)
				(justify mirror)
			)
		)
		(duplicate_pad_numbers_are_jumpers no)
		(fp_rect
			(start 0.2794 0.6477)
			(end -0.2794 -0.6477)
			(stroke
				(width 0)
				(type default)
			)
			(fill no)
			(layer "B.CrtYd")
		)
		(fp_rect
			(start 0.2794 0.6477)
			(end -0.2794 -0.6477)
			(stroke
				(width 0)
				(type default)
			)
			(fill no)
			(layer "B.Fab")
		)
		(pad "1" smd custom
			(at 0 -0.2794 90)
			(size 0.0762 0.0762)
			(layers "B.Cu" "B.Mask" "B.Paste")
			(net "GB_VDDA")
			(options
				(clearance outline)
				(anchor circle)
			)
			(primitives
				(gr_poly
					(pts
						(arc
							(start 0.1524 0.127)
							(mid 0.137521 0.162921)
							(end 0.1016 0.1778)
						)
						(arc
							(start -0.1016 0.1778)
							(mid -0.137521 0.162921)
							(end -0.1524 0.127)
						)
						(arc
							(start -0.1524 -0.127)
							(mid -0.137521 -0.162921)
							(end -0.1016 -0.1778)
						)
						(arc
							(start 0.1016 -0.1778)
							(mid 0.137521 -0.162921)
							(end 0.1524 -0.127)
						)
					)
					(width 0)
					(fill yes)
				)
			)
		)
		(pad "2" smd custom
			(at 0 0.2794 90)
			(size 0.0762 0.0762)
			(layers "B.Cu" "B.Mask" "B.Paste")
			(net "GND")
			(options
				(clearance outline)
				(anchor circle)
			)
			(primitives
				(gr_poly
					(pts
						(arc
							(start 0.1524 0.127)
							(mid 0.137521 0.162921)
							(end 0.1016 0.1778)
						)
						(arc
							(start -0.1016 0.1778)
							(mid -0.137521 0.162921)
							(end -0.1524 0.127)
						)
						(arc
							(start -0.1524 -0.127)
							(mid -0.137521 -0.162921)
							(end -0.1016 -0.1778)
						)
						(arc
							(start 0.1016 -0.1778)
							(mid 0.137521 -0.162921)
							(end 0.1524 -0.127)
						)
					)
					(width 0)
					(fill yes)
				)
			)
		)
	)
	(footprint ""
		(layer "B.Cu")
		(at 106.5022 -65.786 180)
		(property "Reference" "C207"
			(at 0 0 0)
			(layer "B.SilkS")
			(hide yes)
			(effects
				(font
					(size 1.27 1.27)
				)
				(justify mirror)
			)
		)
		(property "Value" "SCD1U6D3V1KX-GP"
			(at 2.8321 -1.7399 180)
			(unlocked yes)
			(layer "B.Fab")
			(hide yes)
			(effects
				(font
					(size 1.016 1.016)
					(thickness 0.1524)
				)
				(justify mirror)
			)
		)
		(property "Device Type" "C0201H13"
			(at 2.8321 -3.2639 180)
			(unlocked yes)
			(layer "B.Fab")
			(hide yes)
			(effects
				(font
					(size 1.016 1.016)
					(thickness 0.1524)
				)
				(justify mirror)
			)
		)
		(duplicate_pad_numbers_are_jumpers no)
		(fp_rect
			(start 0.2794 0.6477)
			(end -0.2794 -0.6477)
			(stroke
				(width 0)
				(type default)
			)
			(fill no)
			(layer "B.CrtYd")
		)
		(fp_rect
			(start 0.2794 0.6477)
			(end -0.2794 -0.6477)
			(stroke
				(width 0)
				(type default)
			)
			(fill no)
			(layer "B.Fab")
		)
		(pad "1" smd custom
			(at 0 -0.2794)
			(size 0.0762 0.0762)
			(layers "B.Cu" "B.Mask" "B.Paste")
			(net "XTAL_VDDA09")
			(options
				(clearance outline)
				(anchor circle)
			)
			(primitives
				(gr_poly
					(pts
						(arc
							(start 0.1524 0.127)
							(mid 0.137521 0.162921)
							(end 0.1016 0.1778)
						)
						(arc
							(start -0.1016 0.1778)
							(mid -0.137521 0.162921)
							(end -0.1524 0.127)
						)
						(arc
							(start -0.1524 -0.127)
							(mid -0.137521 -0.162921)
							(end -0.1016 -0.1778)
						)
						(arc
							(start 0.1016 -0.1778)
							(mid 0.137521 -0.162921)
							(end 0.1524 -0.127)
						)
					)
					(width 0)
					(fill yes)
				)
			)
		)
		(pad "2" smd custom
			(at 0 0.2794)
			(size 0.0762 0.0762)
			(layers "B.Cu" "B.Mask" "B.Paste")
			(net "GND")
			(options
				(clearance outline)
				(anchor circle)
			)
			(primitives
				(gr_poly
					(pts
						(arc
							(start 0.1524 0.127)
							(mid 0.137521 0.162921)
							(end 0.1016 0.1778)
						)
						(arc
							(start -0.1016 0.1778)
							(mid -0.137521 0.162921)
							(end -0.1524 0.127)
						)
						(arc
							(start -0.1524 -0.127)
							(mid -0.137521 -0.162921)
							(end -0.1016 -0.1778)
						)
						(arc
							(start 0.1016 -0.1778)
							(mid 0.137521 -0.162921)
							(end 0.1524 -0.127)
						)
					)
					(width 0)
					(fill yes)
				)
			)
		)
	)
	(footprint ""
		(layer "B.Cu")
		(at 38.592252 -107.66298 90)
		(property "Reference" "C511"
			(at 0 0 90)
			(layer "B.SilkS")
			(hide yes)
			(effects
				(font
					(size 1.27 1.27)
				)
				(justify mirror)
			)
		)
		(property "Value" "SC4D7U25V5KX-1-GP"
			(at 0.0762 -6.1214 90)
			(unlocked yes)
			(layer "B.Fab")
			(hide yes)
			(effects
				(font
					(size 1.016 1.016)
					(thickness 0.1524)
				)
				(justify mirror)
			)
		)
		(property "Device Type" "C805H58"
			(at 0.0762 -8.1534 90)
			(unlocked yes)
			(layer "B.Fab")
			(hide yes)
			(effects
				(font
					(size 1.016 1.016)
					(thickness 0.1524)
				)
				(justify mirror)
			)
		)
		(duplicate_pad_numbers_are_jumpers no)
		(fp_line
			(start -0.635 0)
			(end 0.635 0)
			(stroke
				(width 0.508)
				(type default)
			)
			(layer "B.SilkS")
		)
		(fp_rect
			(start 0.9652 1.778)
			(end -0.9652 -1.778)
			(stroke
				(width 0)
				(type default)
			)
			(fill no)
			(layer "B.CrtYd")
		)
		(fp_poly
			(pts
				(xy 0.9652 -1.778) (xy -0.9652 -1.778) (xy -0.9652 1.778) (xy 0.9652 1.778)
			)
			(stroke
				(width 0)
				(type default)
			)
			(fill no)
			(layer "B.Fab")
		)
		(pad "1" smd rect
			(at 0 -0.9652 270)
			(size 1.397 1.143)
			(layers "B.Cu" "B.Mask" "B.Paste")
			(net "P5V")
		)
		(pad "2" smd rect
			(at 0 0.9652 270)
			(size 1.397 1.143)
			(layers "B.Cu" "B.Mask" "B.Paste")
			(net "GND")
		)
	)
	(footprint ""
		(layer "B.Cu")
		(at 176.202848 -41.87571 90)
		(property "Reference" "C416"
			(at 0 0 90)
			(layer "B.SilkS")
			(hide yes)
			(effects
				(font
					(size 1.27 1.27)
				)
				(justify mirror)
			)
		)
		(property "Value" "SC1U6D3V1MX-GP"
			(at -1.9177 2.0193 90)
			(unlocked yes)
			(layer "B.Fab")
			(hide yes)
			(effects
				(font
					(size 1.016 1.016)
					(thickness 0.1524)
				)
				(justify mirror)
			)
		)
		(property "Device Type" "C0201H14"
			(at -1.9177 0.4953 90)
			(unlocked yes)
			(layer "B.Fab")
			(hide yes)
			(effects
				(font
					(size 1.016 1.016)
					(thickness 0.1524)
				)
				(justify mirror)
			)
		)
		(duplicate_pad_numbers_are_jumpers no)
		(fp_rect
			(start 0.1524 0.3048)
			(end -0.1524 -0.3048)
			(stroke
				(width 0)
				(type default)
			)
			(fill no)
			(layer "B.CrtYd")
		)
		(fp_poly
			(pts
				(xy 0.2794 0.6477) (xy 0.2794 -0.6477) (xy -0.2794 -0.6477) (xy -0.2794 -0.1905) (xy -0.1524 -0.1905)
				(xy -0.1524 -0.3048) (xy 0.1524 -0.3048) (xy 0.1524 0.3048) (xy -0.1524 0.3048) (xy -0.1524 -0.1778)
				(xy -0.2794 -0.1778) (xy -0.2794 0.6477)
			)
			(stroke
				(width 0)
				(type default)
			)
			(fill no)
			(layer "B.CrtYd")
		)
		(fp_rect
			(start 0.2794 0.6477)
			(end -0.2794 -0.6477)
			(stroke
				(width 0)
				(type default)
			)
			(fill no)
			(layer "B.Fab")
		)
		(pad "1" smd custom
			(at 0 -0.2794 270)
			(size 0.0762 0.0762)
			(layers "B.Cu" "B.Mask" "B.Paste")
			(net "P0V975")
			(options
				(clearance outline)
				(anchor circle)
			)
			(primitives
				(gr_poly
					(pts
						(arc
							(start 0.1524 0.127)
							(mid 0.137521 0.162921)
							(end 0.1016 0.1778)
						)
						(arc
							(start -0.1016 0.1778)
							(mid -0.137521 0.162921)
							(end -0.1524 0.127)
						)
						(arc
							(start -0.1524 -0.127)
							(mid -0.137521 -0.162921)
							(end -0.1016 -0.1778)
						)
						(arc
							(start 0.1016 -0.1778)
							(mid 0.137521 -0.162921)
							(end 0.1524 -0.127)
						)
					)
					(width 0)
					(fill yes)
				)
			)
		)
		(pad "2" smd custom
			(at 0 0.2794 270)
			(size 0.0762 0.0762)
			(layers "B.Cu" "B.Mask" "B.Paste")
			(net "GND")
			(options
				(clearance outline)
				(anchor circle)
			)
			(primitives
				(gr_poly
					(pts
						(arc
							(start 0.1524 0.127)
							(mid 0.137521 0.162921)
							(end 0.1016 0.1778)
						)
						(arc
							(start -0.1016 0.1778)
							(mid -0.137521 0.162921)
							(end -0.1524 0.127)
						)
						(arc
							(start -0.1524 -0.127)
							(mid -0.137521 -0.162921)
							(end -0.1016 -0.1778)
						)
						(arc
							(start 0.1016 -0.1778)
							(mid 0.137521 -0.162921)
							(end 0.1524 -0.127)
						)
					)
					(width 0)
					(fill yes)
				)
			)
		)
	)
	(footprint ""
		(layer "B.Cu")
		(at 115.3541 -57.4802)
		(property "Reference" "C266"
			(at 0 0 0)
			(layer "B.SilkS")
			(hide yes)
			(effects
				(font
					(size 1.27 1.27)
				)
				(justify mirror)
			)
		)
		(property "Value" "SCD1U6D3V1KX-GP"
			(at 2.8321 -1.7399 0)
			(unlocked yes)
			(layer "B.Fab")
			(hide yes)
			(effects
				(font
					(size 1.016 1.016)
					(thickness 0.1524)
				)
				(justify mirror)
			)
		)
		(property "Device Type" "C0201H13"
			(at 2.8321 -3.2639 0)
			(unlocked yes)
			(layer "B.Fab")
			(hide yes)
			(effects
				(font
					(size 1.016 1.016)
					(thickness 0.1524)
				)
				(justify mirror)
			)
		)
		(duplicate_pad_numbers_are_jumpers no)
		(fp_rect
			(start 0.2794 0.6477)
			(end -0.2794 -0.6477)
			(stroke
				(width 0)
				(type default)
			)
			(fill no)
			(layer "B.CrtYd")
		)
		(fp_rect
			(start 0.2794 0.6477)
			(end -0.2794 -0.6477)
			(stroke
				(width 0)
				(type default)
			)
			(fill no)
			(layer "B.Fab")
		)
		(pad "1" smd custom
			(at 0 -0.2794 180)
			(size 0.0762 0.0762)
			(layers "B.Cu" "B.Mask" "B.Paste")
			(net "GB_VDDA")
			(options
				(clearance outline)
				(anchor circle)
			)
			(primitives
				(gr_poly
					(pts
						(arc
							(start 0.1524 0.127)
							(mid 0.137521 0.162921)
							(end 0.1016 0.1778)
						)
						(arc
							(start -0.1016 0.1778)
							(mid -0.137521 0.162921)
							(end -0.1524 0.127)
						)
						(arc
							(start -0.1524 -0.127)
							(mid -0.137521 -0.162921)
							(end -0.1016 -0.1778)
						)
						(arc
							(start 0.1016 -0.1778)
							(mid 0.137521 -0.162921)
							(end 0.1524 -0.127)
						)
					)
					(width 0)
					(fill yes)
				)
			)
		)
		(pad "2" smd custom
			(at 0 0.2794 180)
			(size 0.0762 0.0762)
			(layers "B.Cu" "B.Mask" "B.Paste")
			(net "GND")
			(options
				(clearance outline)
				(anchor circle)
			)
			(primitives
				(gr_poly
					(pts
						(arc
							(start 0.1524 0.127)
							(mid 0.137521 0.162921)
							(end 0.1016 0.1778)
						)
						(arc
							(start -0.1016 0.1778)
							(mid -0.137521 0.162921)
							(end -0.1524 0.127)
						)
						(arc
							(start -0.1524 -0.127)
							(mid -0.137521 -0.162921)
							(end -0.1016 -0.1778)
						)
						(arc
							(start 0.1016 -0.1778)
							(mid 0.137521 -0.162921)
							(end 0.1524 -0.127)
						)
					)
					(width 0)
					(fill yes)
				)
			)
		)
	)
	(footprint ""
		(layer "B.Cu")
		(at 172.08627 -28.736798 180)
		(property "Reference" "C389"
			(at 0 0 0)
			(layer "B.SilkS")
			(hide yes)
			(effects
				(font
					(size 1.27 1.27)
				)
				(justify mirror)
			)
		)
		(property "Value" "SCD1U6D3V1KX-GP"
			(at 2.8321 -1.7399 180)
			(unlocked yes)
			(layer "B.Fab")
			(hide yes)
			(effects
				(font
					(size 1.016 1.016)
					(thickness 0.1524)
				)
				(justify mirror)
			)
		)
		(property "Device Type" "C0201H13"
			(at 2.8321 -3.2639 180)
			(unlocked yes)
			(layer "B.Fab")
			(hide yes)
			(effects
				(font
					(size 1.016 1.016)
					(thickness 0.1524)
				)
				(justify mirror)
			)
		)
		(duplicate_pad_numbers_are_jumpers no)
		(fp_rect
			(start 0.2794 0.6477)
			(end -0.2794 -0.6477)
			(stroke
				(width 0)
				(type default)
			)
			(fill no)
			(layer "B.CrtYd")
		)
		(fp_rect
			(start 0.2794 0.6477)
			(end -0.2794 -0.6477)
			(stroke
				(width 0)
				(type default)
			)
			(fill no)
			(layer "B.Fab")
		)
		(pad "1" smd custom
			(at 0 -0.2794)
			(size 0.0762 0.0762)
			(layers "B.Cu" "B.Mask" "B.Paste")
			(net "PCE_AVDD")
			(options
				(clearance outline)
				(anchor circle)
			)
			(primitives
				(gr_poly
					(pts
						(arc
							(start 0.1524 0.127)
							(mid 0.137521 0.162921)
							(end 0.1016 0.1778)
						)
						(arc
							(start -0.1016 0.1778)
							(mid -0.137521 0.162921)
							(end -0.1524 0.127)
						)
						(arc
							(start -0.1524 -0.127)
							(mid -0.137521 -0.162921)
							(end -0.1016 -0.1778)
						)
						(arc
							(start 0.1016 -0.1778)
							(mid 0.137521 -0.162921)
							(end 0.1524 -0.127)
						)
					)
					(width 0)
					(fill yes)
				)
			)
		)
		(pad "2" smd custom
			(at 0 0.2794)
			(size 0.0762 0.0762)
			(layers "B.Cu" "B.Mask" "B.Paste")
			(net "GND")
			(options
				(clearance outline)
				(anchor circle)
			)
			(primitives
				(gr_poly
					(pts
						(arc
							(start 0.1524 0.127)
							(mid 0.137521 0.162921)
							(end 0.1016 0.1778)
						)
						(arc
							(start -0.1016 0.1778)
							(mid -0.137521 0.162921)
							(end -0.1524 0.127)
						)
						(arc
							(start -0.1524 -0.127)
							(mid -0.137521 -0.162921)
							(end -0.1016 -0.1778)
						)
						(arc
							(start 0.1016 -0.1778)
							(mid 0.137521 -0.162921)
							(end 0.1524 -0.127)
						)
					)
					(width 0)
					(fill yes)
				)
			)
		)
	)
)
